(kicad_pcb
	(version 20260206)
	(generator "pcbnew")
	(generator_version "10.0")
	(general
		(thickness 1.6)
		(legacy_teardrops no)
	)
	(paper "A4")
	(title_block
		(title "netronome-mezz — pcbd0082-001_rev01_jul9_a.brd")
		(comment 1 "Open CloudServer (Microsoft) / footprints 610-619 of 714")
	)
	(layers
		(0 "F.Cu" signal "TOP")
		(4 "In1.Cu" signal "02_GND")
		(6 "In2.Cu" signal "03_SIG")
		(8 "In3.Cu" signal "04_SIG")
		(10 "In4.Cu" signal "05_GND")
		(12 "In5.Cu" signal "06_PWR1")
		(14 "In6.Cu" signal "07_SIG")
		(16 "In7.Cu" signal "08_SIG")
		(18 "In8.Cu" signal "09_GND")
		(2 "B.Cu" signal "BOTTOM")
		(9 "F.Adhes" user "F.Adhesive")
		(11 "B.Adhes" user "B.Adhesive")
		(13 "F.Paste" user "Package Geometry/Pastemask Top")
		(15 "B.Paste" user "Package Geometry/Pastemask Bottom")
		(5 "F.SilkS" user "Ref Des/Silkscreen Top")
		(7 "B.SilkS" user "Ref Des/Silkscreen Bottom")
		(1 "F.Mask" user "Board Geometry/Soldermask Top")
		(3 "B.Mask" user "Board Geometry/Soldermask Bottom")
		(17 "Dwgs.User" user "User.Drawings")
		(19 "Cmts.User" user "User.Comments")
		(21 "Eco1.User" user "User.Eco1")
		(23 "Eco2.User" user "User.Eco2")
		(25 "Edge.Cuts" user "Board Geometry/Outline")
		(27 "Margin" user)
		(31 "F.CrtYd" user "Package Geometry/Place Bound Top")
		(29 "B.CrtYd" user "Package Geometry/Place Bound Bottom")
		(35 "F.Fab" user "Ref Des/Assembly Top")
		(33 "B.Fab" user "Ref Des/Assembly Bottom")
		(45 "User.4" user "COMPVAL_TYPE_BOTTOM")
	)
	(footprint ""
		(layer "B.Cu")
		(at 30.988 32.639)
		(property "Reference" "R175"
			(at -0.02667 4.953 270)
			(unlocked yes)
			(layer "B.SilkS")
			(effects
				(font
					(size 0.7874 0.5842)
					(thickness 0.127)
				)
				(justify left mirror)
			)
		)
		(property "Value" "0"
			(at 0.148158 1.3462 270)
			(unlocked yes)
			(layer "B.Fab")
			(hide yes)
			(effects
				(font
					(size 1.27 0.9652)
					(thickness 0.000001)
				)
				(justify left mirror)
			)
		)
		(property "Device Type" "REST1111"
			(at 0.148158 1.3462 270)
			(unlocked yes)
			(layer "B.Fab")
			(hide yes)
			(effects
				(font
					(size 1.27 0.9652)
					(thickness 0.000001)
				)
				(justify left mirror)
			)
		)
		(duplicate_pad_numbers_are_jumpers no)
		(fp_poly
			(pts
				(xy -0.635 1.0668) (xy -0.635 -1.0668) (xy 0.635 -1.0668) (xy 0.635 1.0668)
			)
			(stroke
				(width 0)
				(type default)
			)
			(fill no)
			(layer "B.CrtYd")
		)
		(fp_line
			(start -0.254 -0.508)
			(end -0.254 0.508)
			(stroke
				(width 0.0254)
				(type default)
			)
			(layer "B.Fab")
		)
		(fp_line
			(start -0.254 0.508)
			(end 0.254 0.508)
			(stroke
				(width 0.0254)
				(type default)
			)
			(layer "B.Fab")
		)
		(fp_line
			(start 0.254 -0.508)
			(end -0.254 -0.508)
			(stroke
				(width 0.0254)
				(type default)
			)
			(layer "B.Fab")
		)
		(fp_line
			(start 0.254 0.508)
			(end 0.254 -0.508)
			(stroke
				(width 0.0254)
				(type default)
			)
			(layer "B.Fab")
		)
		(pad "1" smd rect
			(at 0 -0.4191 180)
			(size 0.508 0.5334)
			(layers "B.Cu" "B.Mask" "B.Paste")
			(net "NFP_CORE_VID3")
		)
		(pad "2" smd rect
			(at 0 0.4191 180)
			(size 0.508 0.5334)
			(layers "B.Cu" "B.Mask" "B.Paste")
			(net "_NFP_CORE_VID3")
		)
		(zone
			(layer "B.Cu")
			(hatch none 0.5)
			(connect_pads
				(clearance 0)
			)
			(min_thickness 0.25)
			(keepout
				(tracks not_allowed)
				(vias allowed)
				(pads allowed)
				(copperpour not_allowed)
				(footprints allowed)
			)
			(placement
				(enabled no)
				(sheetname "")
			)
			(fill
				(thermal_gap 0.5)
				(thermal_bridge_width 0.5)
				(island_removal_mode 0)
			)
			(polygon
				(pts
					(xy 30.9626 32.6136) (xy 30.9626 32.6644) (xy 31.0134 32.6644) (xy 31.0134 32.6136)
				)
			)
		)
	)
	(footprint ""
		(layer "B.Cu")
		(at 82.65099 18.255996)
		(property "Reference" "V2_A-A01"
			(at 0 0 0)
			(layer "B.SilkS")
			(hide yes)
			(effects
				(font
					(size 1.27 1.27)
				)
				(justify mirror)
			)
		)
		(property "Value" ""
			(at 0 0 0)
			(layer "B.Fab")
			(effects
				(font
					(size 1.27 1.27)
				)
				(justify mirror)
			)
		)
		(duplicate_pad_numbers_are_jumpers no)
		(pad "1" thru_hole circle
			(at 0 0 180)
			(size 0.4572 0.4572)
			(drill 0.20574)
			(layers "*.Cu" "*.Mask")
			(remove_unused_layers no)
			(net "DDR0_32A_A1")
			(clearance 0.1143)
			(thermal_gap 0.1143)
		)
	)
	(footprint ""
		(layer "B.Cu")
		(at 69.236971 6.542024 180)
		(property "Reference" "C191"
			(at 0 0 0)
			(layer "B.SilkS")
			(hide yes)
			(effects
				(font
					(size 1.27 1.27)
				)
				(justify mirror)
			)
		)
		(property "Value" ""
			(at 0 0 0)
			(layer "B.Fab")
			(effects
				(font
					(size 1.27 1.27)
				)
				(justify mirror)
			)
		)
		(duplicate_pad_numbers_are_jumpers no)
		(fp_circle
			(center 0 0)
			(end -0.104648 0)
			(stroke
				(width 0.1016)
				(type default)
			)
			(fill no)
			(layer "B.SilkS")
		)
		(fp_poly
			(pts
				(xy 0.381 -0.889) (xy 0.381 0.889) (xy -0.381 0.889) (xy -0.381 -0.889)
			)
			(stroke
				(width 0)
				(type default)
			)
			(fill no)
			(layer "B.CrtYd")
		)
		(fp_line
			(start 0.508 1.016)
			(end 0.508 -1.016)
			(stroke
				(width 0.0254)
				(type default)
			)
			(layer "B.Fab")
		)
		(fp_line
			(start 0.508 -1.016)
			(end 0.254 -1.016)
			(stroke
				(width 0.0254)
				(type default)
			)
			(layer "B.Fab")
		)
		(fp_line
			(start 0.254 -1.016)
			(end -0.508 -1.016)
			(stroke
				(width 0.0254)
				(type default)
			)
			(layer "B.Fab")
		)
		(fp_line
			(start -0.508 1.016)
			(end 0.508 1.016)
			(stroke
				(width 0.0254)
				(type default)
			)
			(layer "B.Fab")
		)
		(fp_line
			(start -0.508 -1.016)
			(end -0.508 1.016)
			(stroke
				(width 0.0254)
				(type default)
			)
			(layer "B.Fab")
		)
		(pad "1" smd custom
			(at 0 -0.500126)
			(size 0.127 0.127)
			(layers "B.Cu" "B.Mask" "B.Paste")
			(net "DDR_VDDQ")
			(options
				(clearance outline)
				(anchor circle)
			)
			(primitives
				(gr_poly
					(pts
						(xy -0.1778 0.254) (xy 0.1778 0.254) (xy 0.254 0.1778) (xy 0.254 -0.1778) (xy 0.1778 -0.254) (xy -0.1778 -0.254)
						(xy -0.254 -0.1778) (xy -0.254 0.1778)
					)
					(width 0)
					(fill yes)
				)
			)
		)
		(pad "2" smd custom
			(at 0 0.500126)
			(size 0.127 0.127)
			(layers "B.Cu" "B.Mask" "B.Paste")
			(net "GND")
			(options
				(clearance outline)
				(anchor circle)
			)
			(primitives
				(gr_poly
					(pts
						(xy -0.1778 0.254) (xy 0.1778 0.254) (xy 0.254 0.1778) (xy 0.254 -0.1778) (xy 0.1778 -0.254) (xy -0.1778 -0.254)
						(xy -0.254 -0.1778) (xy -0.254 0.1778)
					)
					(width 0)
					(fill yes)
				)
			)
		)
	)
	(footprint ""
		(layer "B.Cu")
		(at 57.404 0.762 180)
		(property "Reference" "C159"
			(at 0.145212 0.8763 270)
			(unlocked yes)
			(layer "B.SilkS")
			(effects
				(font
					(size 0.7874 0.5842)
					(thickness 0.127)
				)
				(justify left mirror)
			)
		)
		(property "Value" "0.22UF"
			(at 0.091846 0.2921 90)
			(unlocked yes)
			(layer "B.Fab")
			(hide yes)
			(effects
				(font
					(size 0.7874 0.5842)
					(thickness 0.2032)
				)
				(justify left mirror)
			)
		)
		(property "Device Type" "CAPC0062"
			(at 0.091846 0.2921 90)
			(unlocked yes)
			(layer "B.Fab")
			(hide yes)
			(effects
				(font
					(size 0.7874 0.5842)
					(thickness 0.2032)
				)
				(justify left mirror)
			)
		)
		(duplicate_pad_numbers_are_jumpers no)
		(fp_poly
			(pts
				(xy -0.635 1.0668) (xy -0.635 -1.0668) (xy 0.635 -1.0668) (xy 0.635 1.0668)
			)
			(stroke
				(width 0)
				(type default)
			)
			(fill no)
			(layer "B.CrtYd")
		)
		(fp_line
			(start 0.254 0.508)
			(end 0.254 -0.508)
			(stroke
				(width 0.0254)
				(type default)
			)
			(layer "B.Fab")
		)
		(fp_line
			(start 0.254 -0.508)
			(end -0.254 -0.508)
			(stroke
				(width 0.0254)
				(type default)
			)
			(layer "B.Fab")
		)
		(fp_line
			(start -0.254 0.508)
			(end 0.254 0.508)
			(stroke
				(width 0.0254)
				(type default)
			)
			(layer "B.Fab")
		)
		(fp_line
			(start -0.254 -0.508)
			(end -0.254 0.508)
			(stroke
				(width 0.0254)
				(type default)
			)
			(layer "B.Fab")
		)
		(pad "1" smd rect
			(at 0 -0.4191)
			(size 0.508 0.5334)
			(layers "B.Cu" "B.Mask" "B.Paste")
			(net "_NFP_PCIE0_PER3_P")
		)
		(pad "2" smd rect
			(at 0 0.4191)
			(size 0.508 0.5334)
			(layers "B.Cu" "B.Mask" "B.Paste")
			(net "NFP_PCIE0_PER3_P")
		)
		(zone
			(layer "B.Cu")
			(hatch none 0.5)
			(connect_pads
				(clearance 0)
			)
			(min_thickness 0.25)
			(keepout
				(tracks not_allowed)
				(vias allowed)
				(pads allowed)
				(copperpour not_allowed)
				(footprints allowed)
			)
			(placement
				(enabled no)
				(sheetname "")
			)
			(fill
				(thermal_gap 0.5)
				(thermal_bridge_width 0.5)
				(island_removal_mode 0)
			)
			(polygon
				(pts
					(xy 57.4294 0.7874) (xy 57.4294 0.7366) (xy 57.3786 0.7366) (xy 57.3786 0.7874)
				)
			)
		)
	)
	(footprint ""
		(layer "B.Cu")
		(at 81.850992 30.612994)
		(property "Reference" "V3_A-BA1"
			(at 0 0 0)
			(layer "B.SilkS")
			(hide yes)
			(effects
				(font
					(size 1.27 1.27)
				)
				(justify mirror)
			)
		)
		(property "Value" ""
			(at 0 0 0)
			(layer "B.Fab")
			(effects
				(font
					(size 1.27 1.27)
				)
				(justify mirror)
			)
		)
		(duplicate_pad_numbers_are_jumpers no)
		(pad "1" thru_hole circle
			(at 0 0 180)
			(size 0.4572 0.4572)
			(drill 0.20574)
			(layers "*.Cu" "*.Mask")
			(remove_unused_layers no)
			(net "DDR0_32A_BA1")
			(clearance 0.1143)
			(thermal_gap 0.1143)
		)
	)
	(footprint ""
		(layer "B.Cu")
		(at 51.469036 0.762 180)
		(property "Reference" "C149"
			(at 0.145212 0.8763 270)
			(unlocked yes)
			(layer "B.SilkS")
			(effects
				(font
					(size 0.7874 0.5842)
					(thickness 0.127)
				)
				(justify left mirror)
			)
		)
		(property "Value" "0.22UF"
			(at 0.091846 0.2921 90)
			(unlocked yes)
			(layer "B.Fab")
			(hide yes)
			(effects
				(font
					(size 0.7874 0.5842)
					(thickness 0.2032)
				)
				(justify left mirror)
			)
		)
		(property "Device Type" "CAPC0062"
			(at 0.091846 0.2921 90)
			(unlocked yes)
			(layer "B.Fab")
			(hide yes)
			(effects
				(font
					(size 0.7874 0.5842)
					(thickness 0.2032)
				)
				(justify left mirror)
			)
		)
		(duplicate_pad_numbers_are_jumpers no)
		(fp_poly
			(pts
				(xy -0.635 1.0668) (xy -0.635 -1.0668) (xy 0.635 -1.0668) (xy 0.635 1.0668)
			)
			(stroke
				(width 0)
				(type default)
			)
			(fill no)
			(layer "B.CrtYd")
		)
		(fp_line
			(start 0.254 0.508)
			(end 0.254 -0.508)
			(stroke
				(width 0.0254)
				(type default)
			)
			(layer "B.Fab")
		)
		(fp_line
			(start 0.254 -0.508)
			(end -0.254 -0.508)
			(stroke
				(width 0.0254)
				(type default)
			)
			(layer "B.Fab")
		)
		(fp_line
			(start -0.254 0.508)
			(end 0.254 0.508)
			(stroke
				(width 0.0254)
				(type default)
			)
			(layer "B.Fab")
		)
		(fp_line
			(start -0.254 -0.508)
			(end -0.254 0.508)
			(stroke
				(width 0.0254)
				(type default)
			)
			(layer "B.Fab")
		)
		(pad "1" smd rect
			(at 0 -0.4191)
			(size 0.508 0.5334)
			(layers "B.Cu" "B.Mask" "B.Paste")
			(net "_NFP_PCIE0_PER6_P")
		)
		(pad "2" smd rect
			(at 0 0.4191)
			(size 0.508 0.5334)
			(layers "B.Cu" "B.Mask" "B.Paste")
			(net "NFP_PCIE0_PER6_P")
		)
		(zone
			(layer "B.Cu")
			(hatch none 0.5)
			(connect_pads
				(clearance 0)
			)
			(min_thickness 0.25)
			(keepout
				(tracks not_allowed)
				(vias allowed)
				(pads allowed)
				(copperpour not_allowed)
				(footprints allowed)
			)
			(placement
				(enabled no)
				(sheetname "")
			)
			(fill
				(thermal_gap 0.5)
				(thermal_bridge_width 0.5)
				(island_removal_mode 0)
			)
			(polygon
				(pts
					(xy 51.494436 0.7874) (xy 51.494436 0.7366) (xy 51.443636 0.7366) (xy 51.443636 0.7874)
				)
			)
		)
	)
	(footprint ""
		(layer "B.Cu")
		(at 50.1015 18.542 90)
		(property "Reference" "C10"
			(at 0.22733 3.683 0)
			(unlocked yes)
			(layer "B.SilkS")
			(effects
				(font
					(size 0.7874 0.5842)
					(thickness 0.127)
				)
				(justify left mirror)
			)
		)
		(property "Value" "22UF"
			(at 0.148158 1.7526 0)
			(unlocked yes)
			(layer "B.Fab")
			(hide yes)
			(effects
				(font
					(size 1.27 0.9652)
					(thickness 0.000001)
				)
				(justify left mirror)
			)
		)
		(property "Device Type" "CAPC0063"
			(at 0.148158 1.7526 0)
			(unlocked yes)
			(layer "B.Fab")
			(hide yes)
			(effects
				(font
					(size 1.27 0.9652)
					(thickness 0.000001)
				)
				(justify left mirror)
			)
		)
		(duplicate_pad_numbers_are_jumpers no)
		(fp_circle
			(center 0 0)
			(end 0 0.127)
			(stroke
				(width 0.2032)
				(type default)
			)
			(fill no)
			(layer "B.SilkS")
		)
		(fp_poly
			(pts
				(xy -0.7874 -1.6637) (xy 0.7874 -1.6637) (xy 0.7874 1.6637) (xy -0.7874 1.6637)
			)
			(stroke
				(width 0)
				(type default)
			)
			(fill no)
			(layer "B.CrtYd")
		)
		(fp_line
			(start 0.4064 -0.7874)
			(end -0.4064 -0.7874)
			(stroke
				(width 0.0254)
				(type default)
			)
			(layer "B.Fab")
		)
		(fp_line
			(start -0.4064 -0.7874)
			(end -0.4064 0.8128)
			(stroke
				(width 0.0254)
				(type default)
			)
			(layer "B.Fab")
		)
		(fp_line
			(start 0.4064 0.8128)
			(end 0.4064 -0.7874)
			(stroke
				(width 0.0254)
				(type default)
			)
			(layer "B.Fab")
		)
		(fp_line
			(start -0.4064 0.8128)
			(end 0.4064 0.8128)
			(stroke
				(width 0.0254)
				(type default)
			)
			(layer "B.Fab")
		)
		(pad "1" smd rect
			(at 0 -0.8001 270)
			(size 0.8636 0.9652)
			(layers "B.Cu" "B.Mask" "B.Paste")
			(net "VDD_CORE")
		)
		(pad "2" smd rect
			(at 0 0.8001 270)
			(size 0.8636 0.9652)
			(layers "B.Cu" "B.Mask" "B.Paste")
			(net "GND")
		)
		(zone
			(layer "B.Cu")
			(hatch none 0.5)
			(connect_pads
				(clearance 0)
			)
			(min_thickness 0.25)
			(keepout
				(tracks not_allowed)
				(vias allowed)
				(pads allowed)
				(copperpour not_allowed)
				(footprints allowed)
			)
			(placement
				(enabled no)
				(sheetname "")
			)
			(fill
				(thermal_gap 0.5)
				(thermal_bridge_width 0.5)
				(island_removal_mode 0)
			)
			(polygon
				(pts
					(xy 49.8475 18.4785) (xy 49.8475 18.6055) (xy 50.3555 18.6055) (xy 50.3555 18.4785)
				)
			)
		)
	)
	(footprint ""
		(layer "B.Cu")
		(at 28.321 30.48 -90)
		(property "Reference" "C118"
			(at 0.02667 0.762 0)
			(unlocked yes)
			(layer "B.SilkS")
			(effects
				(font
					(size 0.7874 0.5842)
					(thickness 0.127)
				)
				(justify left mirror)
			)
		)
		(property "Value" "0.1UF"
			(at 0.091846 0.2921 180)
			(unlocked yes)
			(layer "B.Fab")
			(hide yes)
			(effects
				(font
					(size 0.7874 0.5842)
					(thickness 0.2032)
				)
				(justify left mirror)
			)
		)
		(property "Device Type" "CAPC0073"
			(at 0.091846 0.2921 180)
			(unlocked yes)
			(layer "B.Fab")
			(hide yes)
			(effects
				(font
					(size 0.7874 0.5842)
					(thickness 0.2032)
				)
				(justify left mirror)
			)
		)
		(duplicate_pad_numbers_are_jumpers no)
		(fp_poly
			(pts
				(xy -0.635 1.0668) (xy -0.635 -1.0668) (xy 0.635 -1.0668) (xy 0.635 1.0668)
			)
			(stroke
				(width 0)
				(type default)
			)
			(fill no)
			(layer "B.CrtYd")
		)
		(fp_line
			(start -0.254 0.508)
			(end 0.254 0.508)
			(stroke
				(width 0.0254)
				(type default)
			)
			(layer "B.Fab")
		)
		(fp_line
			(start 0.254 0.508)
			(end 0.254 -0.508)
			(stroke
				(width 0.0254)
				(type default)
			)
			(layer "B.Fab")
		)
		(fp_line
			(start -0.254 -0.508)
			(end -0.254 0.508)
			(stroke
				(width 0.0254)
				(type default)
			)
			(layer "B.Fab")
		)
		(fp_line
			(start 0.254 -0.508)
			(end -0.254 -0.508)
			(stroke
				(width 0.0254)
				(type default)
			)
			(layer "B.Fab")
		)
		(pad "1" smd rect
			(at 0 -0.4191 90)
			(size 0.508 0.5334)
			(layers "B.Cu" "B.Mask" "B.Paste")
			(net "EXT_3.3V")
		)
		(pad "2" smd rect
			(at 0 0.4191 90)
			(size 0.508 0.5334)
			(layers "B.Cu" "B.Mask" "B.Paste")
			(net "GND")
		)
		(zone
			(layer "B.Cu")
			(hatch none 0.5)
			(connect_pads
				(clearance 0)
			)
			(min_thickness 0.25)
			(keepout
				(tracks not_allowed)
				(vias allowed)
				(pads allowed)
				(copperpour not_allowed)
				(footprints allowed)
			)
			(placement
				(enabled no)
				(sheetname "")
			)
			(fill
				(thermal_gap 0.5)
				(thermal_bridge_width 0.5)
				(island_removal_mode 0)
			)
			(polygon
				(pts
					(xy 28.3464 30.4546) (xy 28.2956 30.4546) (xy 28.2956 30.5054) (xy 28.3464 30.5054)
				)
			)
		)
	)
	(footprint ""
		(layer "B.Cu")
		(at 66.802 25.4 180)
		(property "Reference" "R124"
			(at -0.86233 -0.381 270)
			(unlocked yes)
			(layer "B.SilkS")
			(effects
				(font
					(size 0.7874 0.5842)
					(thickness 0.127)
				)
				(justify mirror)
			)
		)
		(property "Value" ""
			(at 0 0 0)
			(layer "B.Fab")
			(effects
				(font
					(size 1.27 1.27)
				)
				(justify mirror)
			)
		)
		(duplicate_pad_numbers_are_jumpers no)
		(fp_circle
			(center 0 0)
			(end -0.104648 0)
			(stroke
				(width 0.1016)
				(type default)
			)
			(fill no)
			(layer "B.SilkS")
		)
		(fp_poly
			(pts
				(xy 0.381 -0.889) (xy 0.381 0.889) (xy -0.381 0.889) (xy -0.381 -0.889)
			)
			(stroke
				(width 0)
				(type default)
			)
			(fill no)
			(layer "B.CrtYd")
		)
		(fp_line
			(start 0.508 1.016)
			(end 0.508 -1.016)
			(stroke
				(width 0.0254)
				(type default)
			)
			(layer "B.Fab")
		)
		(fp_line
			(start 0.508 -1.016)
			(end 0.254 -1.016)
			(stroke
				(width 0.0254)
				(type default)
			)
			(layer "B.Fab")
		)
		(fp_line
			(start 0.254 -1.016)
			(end -0.508 -1.016)
			(stroke
				(width 0.0254)
				(type default)
			)
			(layer "B.Fab")
		)
		(fp_line
			(start -0.508 1.016)
			(end 0.508 1.016)
			(stroke
				(width 0.0254)
				(type default)
			)
			(layer "B.Fab")
		)
		(fp_line
			(start -0.508 -1.016)
			(end -0.508 1.016)
			(stroke
				(width 0.0254)
				(type default)
			)
			(layer "B.Fab")
		)
		(pad "1" smd custom
			(at 0 -0.500126)
			(size 0.127 0.127)
			(layers "B.Cu" "B.Mask" "B.Paste")
			(net "GND")
			(options
				(clearance outline)
				(anchor circle)
			)
			(primitives
				(gr_poly
					(pts
						(xy -0.1778 0.254) (xy 0.1778 0.254) (xy 0.254 0.1778) (xy 0.254 -0.1778) (xy 0.1778 -0.254) (xy -0.1778 -0.254)
						(xy -0.254 -0.1778) (xy -0.254 0.1778)
					)
					(width 0)
					(fill yes)
				)
			)
		)
		(pad "2" smd custom
			(at 0 0.500126)
			(size 0.127 0.127)
			(layers "B.Cu" "B.Mask" "B.Paste")
			(net "6N3961")
			(options
				(clearance outline)
				(anchor circle)
			)
			(primitives
				(gr_poly
					(pts
						(xy -0.1778 0.254) (xy 0.1778 0.254) (xy 0.254 0.1778) (xy 0.254 -0.1778) (xy 0.1778 -0.254) (xy -0.1778 -0.254)
						(xy -0.254 -0.1778) (xy -0.254 0.1778)
					)
					(width 0)
					(fill yes)
				)
			)
		)
	)
	(footprint ""
		(layer "B.Cu")
		(at 77.051002 25.813004)
		(property "Reference" "V_A-CB7"
			(at 0 0 0)
			(layer "B.SilkS")
			(hide yes)
			(effects
				(font
					(size 1.27 1.27)
				)
				(justify mirror)
			)
		)
		(property "Value" ""
			(at 0 0 0)
			(layer "B.Fab")
			(effects
				(font
					(size 1.27 1.27)
				)
				(justify mirror)
			)
		)
		(duplicate_pad_numbers_are_jumpers no)
		(pad "1" thru_hole circle
			(at 0 0 180)
			(size 0.4572 0.4572)
			(drill 0.20574)
			(layers "*.Cu" "*.Mask")
			(remove_unused_layers no)
			(net "DDR0_32A_CB7")
			(clearance 0.1143)
			(thermal_gap 0.1143)
		)
	)
)
